FILE_TYPE = MULTI_PHYS_TABLE;

PART 'PCA9306DP1'

{========================================================================================}
:VALUE        | PART_TYPE | MATERIAL | PART_NUMBER      = PART_NUMBER   | JEDEC_TYPE | DESCRIPTION                     | MANUFTR | MANUF_PN     | RD_CMPLS_LVL | CMPLS_LVL | FROM_PJ    | CLASS | DIP_SMD | DATA              | EE_CHECK_LIST | FP_ECN | PSL | LIFECYCLE     | CREATOR | STANDARD        | CREATEDAY  | STATUS ;
{========================================================================================}
 'PCA9306DP1' | 'SMLF'    | 'IC'     | 'AL009306K04'(!) = 'AL009306K04' |'TSSOP8_3'| 'IC OTHER(8P)PCA9306DP1(TSSOP)' | 'NXP'   | 'PCA9306DP1' | 'EP(V1)'     | ''        | 'T2L-MARK' | 'IC'  | ''      | 'NXP_PCA9306.pdf' | ''            | ''     | ''  | ''               | ''      | ''               | '20120224' | ''    
 'PCA9306DP1' | 'SMLF'    | 'EMPTY'  | 'AL009306K04'(!) = 'AL009306K04' |'TSSOP8_3'| 'IC OTHER(8P)PCA9306DP1(TSSOP)' | 'NXP'   | 'PCA9306DP1' | 'EP(V1)'     | ''        | 'T2L-MARK' | 'IC'  | ''      | 'NXP_PCA9306.pdf' | ''            | ''     | ''  | ''               | ''      | ''               | '20120224' | ''    

END_PART

END.

